(kicad_pcb
	(version 20260206)
	(generator "pcbnew")
	(generator_version "10.0")
	(general
		(thickness 1.6)
		(legacy_teardrops no)
	)
	(paper "A4")
	(title_block
		(title "Bryce Canyon_SCC_16316-1_OCP.brd")
		(comment 1 "Bryce Canyon / footprints 992-1000 of 1561")
	)
	(layers
		(0 "F.Cu" signal "TOP")
		(4 "In1.Cu" signal "L2GND")
		(6 "In2.Cu" signal "L3")
		(8 "In3.Cu" signal "L4VCC")
		(10 "In4.Cu" signal "L5VCC")
		(12 "In5.Cu" signal "L6")
		(14 "In6.Cu" signal "L7GND")
		(2 "B.Cu" signal "BOTTOM")
		(9 "F.Adhes" user "F.Adhesive")
		(11 "B.Adhes" user "B.Adhesive")
		(13 "F.Paste" user "Package Geometry/Pastemask Top")
		(15 "B.Paste" user "Package Geometry/Pastemask Bottom")
		(5 "F.SilkS" user "Ref Des/Silkscreen Top")
		(7 "B.SilkS" user "Ref Des/Silkscreen Bottom")
		(1 "F.Mask" user "Board Geometry/Soldermask Top")
		(3 "B.Mask" user "Board Geometry/Soldermask Bottom")
		(17 "Dwgs.User" user "User.Drawings")
		(19 "Cmts.User" user "User.Comments")
		(21 "Eco1.User" user "User.Eco1")
		(23 "Eco2.User" user "User.Eco2")
		(25 "Edge.Cuts" user "Board Geometry/Outline")
		(27 "Margin" user)
		(31 "F.CrtYd" user "Package Geometry/Place Bound Top")
		(29 "B.CrtYd" user "Package Geometry/Place Bound Bottom")
		(35 "F.Fab" user "Ref Des/Assembly Top")
		(33 "B.Fab" user "Ref Des/Assembly Bottom")
	)
	(footprint ""
		(layer "B.Cu")
		(at 62.1792 -58.6486 -90)
		(property "Reference" "C617"
			(at 0 0 90)
			(layer "B.SilkS")
			(hide yes)
			(effects
				(font
					(size 1.27 1.27)
				)
				(justify mirror)
			)
		)
		(property "Value" "SC10U6D3V5KX-4GP"
			(at 0.0762 -6.1214 270)
			(unlocked yes)
			(layer "B.Fab")
			(hide yes)
			(effects
				(font
					(size 1.016 1.016)
					(thickness 0.1524)
				)
				(justify mirror)
			)
		)
		(property "Device Type" "C805H58"
			(at 0.0762 -8.1534 270)
			(unlocked yes)
			(layer "B.Fab")
			(hide yes)
			(effects
				(font
					(size 1.016 1.016)
					(thickness 0.1524)
				)
				(justify mirror)
			)
		)
		(duplicate_pad_numbers_are_jumpers no)
		(fp_line
			(start -0.635 0)
			(end 0.635 0)
			(stroke
				(width 0.508)
				(type default)
			)
			(layer "B.SilkS")
		)
		(fp_rect
			(start 0.9652 1.778)
			(end -0.9652 -1.778)
			(stroke
				(width 0)
				(type default)
			)
			(fill no)
			(layer "B.CrtYd")
		)
		(fp_poly
			(pts
				(xy 0.9652 -1.778) (xy -0.9652 -1.778) (xy -0.9652 1.778) (xy 0.9652 1.778)
			)
			(stroke
				(width 0)
				(type default)
			)
			(fill no)
			(layer "B.Fab")
		)
		(pad "1" smd rect
			(at 0 -0.9652 90)
			(size 1.397 1.143)
			(layers "B.Cu" "B.Mask" "B.Paste")
			(net "P0V9")
		)
		(pad "2" smd rect
			(at 0 0.9652 90)
			(size 1.397 1.143)
			(layers "B.Cu" "B.Mask" "B.Paste")
			(net "GND")
		)
	)
	(footprint ""
		(layer "B.Cu")
		(at 90.1192 -82.6008)
		(property "Reference" "U23"
			(at 0 0 0)
			(layer "B.SilkS")
			(hide yes)
			(effects
				(font
					(size 1.27 1.27)
				)
				(justify mirror)
			)
		)
		(property "Value" "TPS3808G01DBVT-GP"
			(at 0.0254 -11.9634 0)
			(unlocked yes)
			(layer "B.Fab")
			(hide yes)
			(effects
				(font
					(size 1.016 1.016)
					(thickness 0.1524)
				)
				(justify mirror)
			)
		)
		(property "Device Type" "SOT-6H58"
			(at 0.0254 -13.5636 0)
			(unlocked yes)
			(layer "B.Fab")
			(hide yes)
			(effects
				(font
					(size 1.016 1.016)
					(thickness 0.1524)
				)
				(justify mirror)
			)
		)
		(duplicate_pad_numbers_are_jumpers no)
		(fp_line
			(start -1.7145 -0.5842)
			(end 1.9685 -0.5842)
			(stroke
				(width 0.1524)
				(type default)
			)
			(layer "B.SilkS")
		)
		(fp_line
			(start -1.7145 0.5842)
			(end -1.7145 -0.5842)
			(stroke
				(width 0.1524)
				(type default)
			)
			(layer "B.SilkS")
		)
		(fp_line
			(start 1.5621 0)
			(end 1.9685 0.4064)
			(stroke
				(width 0.1524)
				(type default)
			)
			(layer "B.SilkS")
		)
		(fp_line
			(start 1.9685 -0.5842)
			(end 1.9685 0.5842)
			(stroke
				(width 0.1524)
				(type default)
			)
			(layer "B.SilkS")
		)
		(fp_line
			(start 1.9685 -0.4064)
			(end 1.5621 0)
			(stroke
				(width 0.1524)
				(type default)
			)
			(layer "B.SilkS")
		)
		(fp_line
			(start 1.9685 0.5842)
			(end -1.7145 0.5842)
			(stroke
				(width 0.1524)
				(type default)
			)
			(layer "B.SilkS")
		)
		(fp_line
			(start 1.9685 0.5842)
			(end 1.9685 2.3622)
			(stroke
				(width 0.508)
				(type default)
			)
			(layer "B.SilkS")
		)
		(fp_poly
			(pts
				(xy 1.27 -0.635) (xy -1.27 -0.635) (xy -1.27 0.635) (xy 1.27 0.635)
			)
			(stroke
				(width 0)
				(type default)
			)
			(fill yes)
			(layer "B.SilkS")
		)
		(fp_rect
			(start 1.9685 2.3622)
			(end -1.9685 -2.3622)
			(stroke
				(width 0)
				(type default)
			)
			(fill no)
			(layer "B.CrtYd")
		)
		(fp_poly
			(pts
				(xy 1.9685 -2.3622) (xy -1.9685 -2.3622) (xy -1.9685 2.3622) (xy 1.9685 2.3622)
			)
			(stroke
				(width 0)
				(type default)
			)
			(fill no)
			(layer "B.Fab")
		)
		(pad "1" smd rect
			(at 0.9525 1.3462 180)
			(size 0.5842 1.016)
			(layers "B.Cu" "B.Mask" "B.Paste")
			(net "EXP_RESET_R_U23_N")
		)
		(pad "2" smd rect
			(at 0 1.3462 180)
			(size 0.5842 1.016)
			(layers "B.Cu" "B.Mask" "B.Paste")
			(net "GND")
		)
		(pad "3" smd rect
			(at -0.9525 1.3462 180)
			(size 0.5842 1.016)
			(layers "B.Cu" "B.Mask" "B.Paste")
			(net "RESET_MR#")
		)
		(pad "4" smd rect
			(at -0.9525 -1.3462 180)
			(size 0.5842 1.016)
			(layers "B.Cu" "B.Mask" "B.Paste")
			(net "RESET_CT")
		)
		(pad "5" smd rect
			(at 0 -1.3462 180)
			(size 0.5842 1.016)
			(layers "B.Cu" "B.Mask" "B.Paste")
			(net "RESET_SENSE")
		)
		(pad "6" smd rect
			(at 0.9525 -1.3462 180)
			(size 0.5842 1.016)
			(layers "B.Cu" "B.Mask" "B.Paste")
			(net "P3V3")
		)
	)
	(footprint ""
		(layer "B.Cu")
		(at 160.472374 -33.403032 180)
		(property "Reference" "C371"
			(at 0 0 0)
			(layer "B.SilkS")
			(hide yes)
			(effects
				(font
					(size 1.27 1.27)
				)
				(justify mirror)
			)
		)
		(property "Value" "SC22U6D3V3MX-9-GP-U"
			(at 0 -2.8194 180)
			(unlocked yes)
			(layer "B.Fab")
			(hide yes)
			(effects
				(font
					(size 1.016 1.016)
					(thickness 0.1524)
				)
				(justify mirror)
			)
		)
		(property "Device Type" "C603H40"
			(at 0 -4.3434 180)
			(unlocked yes)
			(layer "B.Fab")
			(hide yes)
			(effects
				(font
					(size 1.016 1.016)
					(thickness 0.1524)
				)
				(justify mirror)
			)
		)
		(duplicate_pad_numbers_are_jumpers no)
		(fp_line
			(start -0.508 0)
			(end 0.508 0)
			(stroke
				(width 0.2032)
				(type default)
			)
			(layer "B.SilkS")
		)
		(fp_rect
			(start 0.5842 1.3335)
			(end -0.5842 -1.3335)
			(stroke
				(width 0)
				(type default)
			)
			(fill no)
			(layer "B.CrtYd")
		)
		(fp_rect
			(start 0.5842 1.3335)
			(end -0.5842 -1.3335)
			(stroke
				(width 0)
				(type default)
			)
			(fill no)
			(layer "B.Fab")
		)
		(pad "1" smd custom
			(at 0 -0.762)
			(size 0.2159 0.2159)
			(layers "B.Cu" "B.Mask" "B.Paste")
			(net "SAS0_VDDH")
			(options
				(clearance outline)
				(anchor circle)
			)
			(primitives
				(gr_poly
					(pts
						(arc
							(start -0.3302 0.4318)
							(mid -0.402042 0.402042)
							(end -0.4318 0.3302)
						)
						(arc
							(start -0.4318 -0.3302)
							(mid -0.402042 -0.402042)
							(end -0.3302 -0.4318)
						)
						(arc
							(start 0.3302 -0.4318)
							(mid 0.402042 -0.402042)
							(end 0.4318 -0.3302)
						)
						(arc
							(start 0.4318 0.3302)
							(mid 0.402042 0.402042)
							(end 0.3302 0.4318)
						)
					)
					(width 0)
					(fill yes)
				)
			)
		)
		(pad "2" smd custom
			(at 0 0.762)
			(size 0.2159 0.2159)
			(layers "B.Cu" "B.Mask" "B.Paste")
			(net "GND")
			(options
				(clearance outline)
				(anchor circle)
			)
			(primitives
				(gr_poly
					(pts
						(arc
							(start -0.3302 0.4318)
							(mid -0.402042 0.402042)
							(end -0.4318 0.3302)
						)
						(arc
							(start -0.4318 -0.3302)
							(mid -0.402042 -0.402042)
							(end -0.3302 -0.4318)
						)
						(arc
							(start 0.3302 -0.4318)
							(mid 0.402042 -0.402042)
							(end 0.4318 -0.3302)
						)
						(arc
							(start 0.4318 0.3302)
							(mid 0.402042 0.402042)
							(end 0.3302 0.4318)
						)
					)
					(width 0)
					(fill yes)
				)
			)
		)
	)
	(footprint ""
		(layer "B.Cu")
		(at 167.6019 -12.319)
		(property "Reference" "R577"
			(at 0 0 0)
			(layer "B.SilkS")
			(hide yes)
			(effects
				(font
					(size 1.27 1.27)
				)
				(justify mirror)
			)
		)
		(property "Value" "10KR2F-2-GP"
			(at -0.064008 -3.993896 0)
			(unlocked yes)
			(layer "B.Fab")
			(hide yes)
			(effects
				(font
					(size 1.016 1.016)
					(thickness 0.1524)
				)
				(justify mirror)
			)
		)
		(property "Device Type" "R402H16"
			(at -0.064008 -5.517896 0)
			(unlocked yes)
			(layer "B.Fab")
			(hide yes)
			(effects
				(font
					(size 1.016 1.016)
					(thickness 0.1524)
				)
				(justify mirror)
			)
		)
		(duplicate_pad_numbers_are_jumpers no)
		(fp_line
			(start -0.508 -0.9398)
			(end 0.508 -0.9398)
			(stroke
				(width 0.1524)
				(type default)
			)
			(layer "B.SilkS")
		)
		(fp_line
			(start 0.508 -0.9398)
			(end 0.508 0.9398)
			(stroke
				(width 0.1524)
				(type default)
			)
			(layer "B.SilkS")
		)
		(fp_rect
			(start 0.508 0.9398)
			(end -0.508 -0.9398)
			(stroke
				(width 0)
				(type default)
			)
			(fill no)
			(layer "B.CrtYd")
		)
		(fp_rect
			(start 0.508 0.9398)
			(end -0.508 -0.9398)
			(stroke
				(width 0)
				(type default)
			)
			(fill no)
			(layer "B.Fab")
		)
		(pad "1" smd custom
			(at 0 -0.4445 180)
			(size 0.1397 0.1397)
			(layers "B.Cu" "B.Mask" "B.Paste")
			(net "P3V3")
			(options
				(clearance outline)
				(anchor circle)
			)
			(primitives
				(gr_poly
					(pts
						(arc
							(start -0.1778 0.2794)
							(mid -0.249642 0.249642)
							(end -0.2794 0.1778)
						)
						(arc
							(start -0.2794 -0.1778)
							(mid -0.249642 -0.249642)
							(end -0.1778 -0.2794)
						)
						(arc
							(start 0.1778 -0.2794)
							(mid 0.249642 -0.249642)
							(end 0.2794 -0.1778)
						)
						(arc
							(start 0.2794 0.1778)
							(mid 0.249642 0.249642)
							(end 0.1778 0.2794)
						)
					)
					(width 0)
					(fill yes)
				)
			)
		)
		(pad "2" smd custom
			(at 0 0.4445 180)
			(size 0.1397 0.1397)
			(layers "B.Cu" "B.Mask" "B.Paste")
			(net "U50_OE")
			(options
				(clearance outline)
				(anchor circle)
			)
			(primitives
				(gr_poly
					(pts
						(arc
							(start -0.1778 0.2794)
							(mid -0.249642 0.249642)
							(end -0.2794 0.1778)
						)
						(arc
							(start -0.2794 -0.1778)
							(mid -0.249642 -0.249642)
							(end -0.1778 -0.2794)
						)
						(arc
							(start 0.1778 -0.2794)
							(mid 0.249642 -0.249642)
							(end 0.2794 -0.1778)
						)
						(arc
							(start 0.2794 0.1778)
							(mid 0.249642 0.249642)
							(end 0.1778 0.2794)
						)
					)
					(width 0)
					(fill yes)
				)
			)
		)
	)
	(footprint ""
		(layer "B.Cu")
		(at 107.498134 -74.4982)
		(property "Reference" "TP168"
			(at 0 0 0)
			(layer "B.SilkS")
			(hide yes)
			(effects
				(font
					(size 1.27 1.27)
				)
				(justify mirror)
			)
		)
		(property "Value" "TPAD28-2-GP"
			(at 0.0127 -1.6637 0)
			(unlocked yes)
			(layer "B.Fab")
			(hide yes)
			(effects
				(font
					(size 1.016 1.016)
					(thickness 0.1524)
				)
				(justify mirror)
			)
		)
		(property "Device Type" "TPAD28"
			(at 0.0127 -3.1877 0)
			(unlocked yes)
			(layer "B.Fab")
			(hide yes)
			(effects
				(font
					(size 1.016 1.016)
					(thickness 0.1524)
				)
				(justify mirror)
			)
		)
		(duplicate_pad_numbers_are_jumpers no)
		(fp_poly
			(pts
				(arc
					(start 0.3556 0)
					(mid -0.3556 0)
					(end 0.3556 0)
				)
			)
			(stroke
				(width 0)
				(type default)
			)
			(fill no)
			(layer "B.CrtYd")
		)
		(fp_poly
			(pts
				(arc
					(start 0.6096 0)
					(mid -0.6096 0)
					(end 0.6096 0)
				)
			)
			(stroke
				(width 0)
				(type default)
			)
			(fill no)
			(layer "B.Fab")
		)
		(pad "1" smd circle
			(at 0 0 180)
			(size 0.7112 0.7112)
			(layers "B.Cu" "B.Mask" "B.Paste")
			(net "LED8")
		)
	)
	(footprint ""
		(layer "B.Cu")
		(at 112.6236 -57.4802)
		(property "Reference" "C231"
			(at 0 0 0)
			(layer "B.SilkS")
			(hide yes)
			(effects
				(font
					(size 1.27 1.27)
				)
				(justify mirror)
			)
		)
		(property "Value" "SCD1U6D3V1KX-GP"
			(at 2.8321 -1.7399 0)
			(unlocked yes)
			(layer "B.Fab")
			(hide yes)
			(effects
				(font
					(size 1.016 1.016)
					(thickness 0.1524)
				)
				(justify mirror)
			)
		)
		(property "Device Type" "C0201H13"
			(at 2.8321 -3.2639 0)
			(unlocked yes)
			(layer "B.Fab")
			(hide yes)
			(effects
				(font
					(size 1.016 1.016)
					(thickness 0.1524)
				)
				(justify mirror)
			)
		)
		(duplicate_pad_numbers_are_jumpers no)
		(fp_rect
			(start 0.2794 0.6477)
			(end -0.2794 -0.6477)
			(stroke
				(width 0)
				(type default)
			)
			(fill no)
			(layer "B.CrtYd")
		)
		(fp_rect
			(start 0.2794 0.6477)
			(end -0.2794 -0.6477)
			(stroke
				(width 0)
				(type default)
			)
			(fill no)
			(layer "B.Fab")
		)
		(pad "1" smd custom
			(at 0 -0.2794 180)
			(size 0.0762 0.0762)
			(layers "B.Cu" "B.Mask" "B.Paste")
			(net "GB_VDDA")
			(options
				(clearance outline)
				(anchor circle)
			)
			(primitives
				(gr_poly
					(pts
						(arc
							(start 0.1524 0.127)
							(mid 0.137521 0.162921)
							(end 0.1016 0.1778)
						)
						(arc
							(start -0.1016 0.1778)
							(mid -0.137521 0.162921)
							(end -0.1524 0.127)
						)
						(arc
							(start -0.1524 -0.127)
							(mid -0.137521 -0.162921)
							(end -0.1016 -0.1778)
						)
						(arc
							(start 0.1016 -0.1778)
							(mid 0.137521 -0.162921)
							(end 0.1524 -0.127)
						)
					)
					(width 0)
					(fill yes)
				)
			)
		)
		(pad "2" smd custom
			(at 0 0.2794 180)
			(size 0.0762 0.0762)
			(layers "B.Cu" "B.Mask" "B.Paste")
			(net "GND")
			(options
				(clearance outline)
				(anchor circle)
			)
			(primitives
				(gr_poly
					(pts
						(arc
							(start 0.1524 0.127)
							(mid 0.137521 0.162921)
							(end 0.1016 0.1778)
						)
						(arc
							(start -0.1016 0.1778)
							(mid -0.137521 0.162921)
							(end -0.1524 0.127)
						)
						(arc
							(start -0.1524 -0.127)
							(mid -0.137521 -0.162921)
							(end -0.1016 -0.1778)
						)
						(arc
							(start 0.1016 -0.1778)
							(mid 0.137521 -0.162921)
							(end 0.1524 -0.127)
						)
					)
					(width 0)
					(fill yes)
				)
			)
		)
	)
	(footprint ""
		(layer "B.Cu")
		(at 181.6862 -54.4576 -90)
		(property "Reference" "TP102"
			(at 0 0 90)
			(layer "B.SilkS")
			(hide yes)
			(effects
				(font
					(size 1.27 1.27)
				)
				(justify mirror)
			)
		)
		(property "Value" "TPAD28-2-GP"
			(at 0.0127 -1.6637 270)
			(unlocked yes)
			(layer "B.Fab")
			(hide yes)
			(effects
				(font
					(size 1.016 1.016)
					(thickness 0.1524)
				)
				(justify mirror)
			)
		)
		(property "Device Type" "TPAD28"
			(at 0.0127 -3.1877 270)
			(unlocked yes)
			(layer "B.Fab")
			(hide yes)
			(effects
				(font
					(size 1.016 1.016)
					(thickness 0.1524)
				)
				(justify mirror)
			)
		)
		(duplicate_pad_numbers_are_jumpers no)
		(fp_poly
			(pts
				(arc
					(start 0 -0.3556)
					(mid 0 0.3556)
					(end 0 -0.3556)
				)
			)
			(stroke
				(width 0)
				(type default)
			)
			(fill no)
			(layer "B.CrtYd")
		)
		(fp_poly
			(pts
				(arc
					(start 0 -0.6096)
					(mid 0 0.6096)
					(end 0 -0.6096)
				)
			)
			(stroke
				(width 0)
				(type default)
			)
			(fill no)
			(layer "B.Fab")
		)
		(pad "1" smd circle
			(at 0 0 90)
			(size 0.7112 0.7112)
			(layers "B.Cu" "B.Mask" "B.Paste")
			(net "XM_ADDR_0")
		)
	)
	(footprint ""
		(layer "B.Cu")
		(at 101.727 -57.5056 90)
		(property "Reference" "C194"
			(at 0 0 90)
			(layer "B.SilkS")
			(hide yes)
			(effects
				(font
					(size 1.27 1.27)
				)
				(justify mirror)
			)
		)
		(property "Value" "SC1U6D3V1MX-GP"
			(at -1.9177 2.0193 90)
			(unlocked yes)
			(layer "B.Fab")
			(hide yes)
			(effects
				(font
					(size 1.016 1.016)
					(thickness 0.1524)
				)
				(justify mirror)
			)
		)
		(property "Device Type" "C0201H14"
			(at -1.9177 0.4953 90)
			(unlocked yes)
			(layer "B.Fab")
			(hide yes)
			(effects
				(font
					(size 1.016 1.016)
					(thickness 0.1524)
				)
				(justify mirror)
			)
		)
		(duplicate_pad_numbers_are_jumpers no)
		(fp_rect
			(start 0.1524 0.3048)
			(end -0.1524 -0.3048)
			(stroke
				(width 0)
				(type default)
			)
			(fill no)
			(layer "B.CrtYd")
		)
		(fp_poly
			(pts
				(xy 0.2794 0.6477) (xy 0.2794 -0.6477) (xy -0.2794 -0.6477) (xy -0.2794 -0.1905) (xy -0.1524 -0.1905)
				(xy -0.1524 -0.3048) (xy 0.1524 -0.3048) (xy 0.1524 0.3048) (xy -0.1524 0.3048) (xy -0.1524 -0.1778)
				(xy -0.2794 -0.1778) (xy -0.2794 0.6477)
			)
			(stroke
				(width 0)
				(type default)
			)
			(fill no)
			(layer "B.CrtYd")
		)
		(fp_rect
			(start 0.2794 0.6477)
			(end -0.2794 -0.6477)
			(stroke
				(width 0)
				(type default)
			)
			(fill no)
			(layer "B.Fab")
		)
		(pad "1" smd custom
			(at 0 -0.2794 270)
			(size 0.0762 0.0762)
			(layers "B.Cu" "B.Mask" "B.Paste")
			(net "XTAL_VDDA18")
			(options
				(clearance outline)
				(anchor circle)
			)
			(primitives
				(gr_poly
					(pts
						(arc
							(start 0.1524 0.127)
							(mid 0.137521 0.162921)
							(end 0.1016 0.1778)
						)
						(arc
							(start -0.1016 0.1778)
							(mid -0.137521 0.162921)
							(end -0.1524 0.127)
						)
						(arc
							(start -0.1524 -0.127)
							(mid -0.137521 -0.162921)
							(end -0.1016 -0.1778)
						)
						(arc
							(start 0.1016 -0.1778)
							(mid 0.137521 -0.162921)
							(end 0.1524 -0.127)
						)
					)
					(width 0)
					(fill yes)
				)
			)
		)
		(pad "2" smd custom
			(at 0 0.2794 270)
			(size 0.0762 0.0762)
			(layers "B.Cu" "B.Mask" "B.Paste")
			(net "GND")
			(options
				(clearance outline)
				(anchor circle)
			)
			(primitives
				(gr_poly
					(pts
						(arc
							(start 0.1524 0.127)
							(mid 0.137521 0.162921)
							(end 0.1016 0.1778)
						)
						(arc
							(start -0.1016 0.1778)
							(mid -0.137521 0.162921)
							(end -0.1524 0.127)
						)
						(arc
							(start -0.1524 -0.127)
							(mid -0.137521 -0.162921)
							(end -0.1016 -0.1778)
						)
						(arc
							(start 0.1016 -0.1778)
							(mid 0.137521 -0.162921)
							(end 0.1524 -0.127)
						)
					)
					(width 0)
					(fill yes)
				)
			)
		)
	)
	(footprint ""
		(layer "B.Cu")
		(at 70.485 -37.465 90)
		(property "Reference" "L7"
			(at 0 0 90)
			(layer "B.SilkS")
			(hide yes)
			(effects
				(font
					(size 1.27 1.27)
				)
				(justify mirror)
			)
		)
		(property "Value" "MPZ2012S300AT-GP"
			(at 0 -4.2418 90)
			(unlocked yes)
			(layer "B.Fab")
			(hide yes)
			(effects
				(font
					(size 1.016 1.016)
					(thickness 0.1524)
				)
				(justify mirror)
			)
		)
		(property "Device Type" "L805H42"
			(at 0 -5.7912 90)
			(unlocked yes)
			(layer "B.Fab")
			(hide yes)
			(effects
				(font
					(size 1.016 1.016)
					(thickness 0.1524)
				)
				(justify mirror)
			)
		)
		(duplicate_pad_numbers_are_jumpers no)
		(fp_line
			(start 0.889 -1.7018)
			(end -0.889 -1.7018)
			(stroke
				(width 0.1524)
				(type default)
			)
			(layer "B.SilkS")
		)
		(fp_line
			(start -0.889 -1.7018)
			(end -0.889 1.7018)
			(stroke
				(width 0.1524)
				(type default)
			)
			(layer "B.SilkS")
		)
		(fp_line
			(start 0.889 1.7018)
			(end 0.889 -1.7018)
			(stroke
				(width 0.1524)
				(type default)
			)
			(layer "B.SilkS")
		)
		(fp_line
			(start -0.889 1.7018)
			(end 0.889 1.7018)
			(stroke
				(width 0.1524)
				(type default)
			)
			(layer "B.SilkS")
		)
		(fp_rect
			(start 0.9652 1.778)
			(end -0.9652 -1.778)
			(stroke
				(width 0)
				(type default)
			)
			(fill no)
			(layer "B.CrtYd")
		)
		(fp_rect
			(start 0.9652 1.778)
			(end -0.9652 -1.778)
			(stroke
				(width 0)
				(type default)
			)
			(fill no)
			(layer "B.Fab")
		)
		(pad "1" smd rect
			(at 0 -0.9652 270)
			(size 1.397 1.143)
			(layers "B.Cu" "B.Mask" "B.Paste")
			(net "P0V9")
		)
		(pad "2" smd rect
			(at 0 0.9652 270)
			(size 1.397 1.143)
			(layers "B.Cu" "B.Mask" "B.Paste")
			(net "GB_VDDA")
		)
	)
)
